# BASEBOARD_FAB2 (Tioga Pass) — schematic netlist excerpt (pin names and nets, part order shuffled) for the footprints in the layout excerpt that follows; sources: Cadence DE-HDL packaged netlist, KiCad conversion of Wiwynn_Tioga_Pass_MB.brd

C5G48  CAP_A  22.0UF 4V 20% X6S  pkg 0603V  page 242 : A = PVDDQ_ABC ; B = GND
C7W1  CAP_A  0.1UF 16V 10% X7R  pkg 0402V  page 166 : A = P3V3_STBY ; B = GND
C9B9  SC1U10V2KX-4-GP  10%  pkg SMD-BCG6  page 186 : \1\ = P5V_STBY ; \2\ = GND

(kicad_pcb
	(version 20260206)
	(generator "pcbnew")
	(generator_version "10.0")
	(general
		(thickness 1.6)
		(legacy_teardrops no)
	)
	(paper "A4")
	(title_block
		(title "Wiwynn_Tioga_Pass_MB.brd")
		(comment 1 "Tioga Pass / footprints 3923-3925 of 4770")
	)
	(layers
		(0 "F.Cu" signal "TOP")
		(4 "In1.Cu" signal "L2GND")
		(6 "In2.Cu" signal "L3")
		(8 "In3.Cu" signal "L4GND")
		(10 "In4.Cu" signal "L5")
		(12 "In5.Cu" signal "L6GND")
		(14 "In6.Cu" signal "L7VCC")
		(16 "In7.Cu" signal "L8VCC")
		(18 "In8.Cu" signal "L9GND")
		(20 "In9.Cu" signal "L10")
		(22 "In10.Cu" signal "L11GND")
		(24 "In11.Cu" signal "L12")
		(26 "In12.Cu" signal "L13GND")
		(2 "B.Cu" signal "BOTTOM")
		(9 "F.Adhes" user "F.Adhesive")
		(11 "B.Adhes" user "B.Adhesive")
		(13 "F.Paste" user "Package Geometry/Pastemask Top")
		(15 "B.Paste" user "Package Geometry/Pastemask Bottom")
		(5 "F.SilkS" user "Ref Des/Silkscreen Top")
		(7 "B.SilkS" user "Ref Des/Silkscreen Bottom")
		(1 "F.Mask" user "Board Geometry/Soldermask Top")
		(3 "B.Mask" user "Board Geometry/Soldermask Bottom")
		(17 "Dwgs.User" user "User.Drawings")
		(19 "Cmts.User" user "User.Comments")
		(21 "Eco1.User" user "User.Eco1")
		(23 "Eco2.User" user "User.Eco2")
		(25 "Edge.Cuts" user "Board Geometry/Outline")
		(27 "Margin" user)
		(31 "F.CrtYd" user "Package Geometry/Place Bound Top")
		(29 "B.CrtYd" user "Package Geometry/Place Bound Bottom")
		(35 "F.Fab" user "Ref Des/Assembly Top")
		(33 "B.Fab" user "Ref Des/Assembly Bottom")
	)
	(footprint ""
		(layer "B.Cu")
		(at 485.734868 -121.774712 180)
		(property "Reference" "C9B9"
			(at 0 0 0)
			(layer "B.SilkS")
			(hide yes)
			(effects
				(font
					(size 1.27 1.27)
				)
				(justify mirror)
			)
		)
		(property "Value" "*"
			(at -1.1811 -2.8194 180)
			(unlocked yes)
			(layer "B.Fab")
			(hide yes)
			(effects
				(font
					(size 1.27 1.016)
					(thickness 0.1524)
				)
				(justify mirror)
			)
		)
		(property "Device Type" "SC1U10V2KX-4-GP_SMD-BCG6-SC1U1A"
			(at -1.1811 -4.3434 180)
			(unlocked yes)
			(layer "B.Fab")
			(hide yes)
			(effects
				(font
					(size 1.27 1.016)
					(thickness 0.1524)
				)
				(justify mirror)
			)
		)
		(duplicate_pad_numbers_are_jumpers no)
		(fp_rect
			(start 0.4318 0.9525)
			(end -0.4318 -0.9525)
			(stroke
				(width 0)
				(type default)
			)
			(fill no)
			(layer "B.CrtYd")
		)
		(fp_rect
			(start 0.4318 0.9525)
			(end -0.4318 -0.9525)
			(stroke
				(width 0)
				(type default)
			)
			(fill no)
			(layer "B.Fab")
		)
		(pad "1" smd custom
			(at 0 -0.4445)
			(size 0.1524 0.1524)
			(layers "B.Cu" "B.Mask" "B.Paste")
			(net "P5V_STBY")
			(options
				(clearance outline)
				(anchor circle)
			)
			(primitives
				(gr_poly
					(pts
						(arc
							(start 0.3048 0.2032)
							(mid 0.275042 0.275042)
							(end 0.2032 0.3048)
						)
						(arc
							(start -0.2032 0.3048)
							(mid -0.275042 0.275042)
							(end -0.3048 0.2032)
						)
						(arc
							(start -0.3048 -0.2032)
							(mid -0.275042 -0.275042)
							(end -0.2032 -0.3048)
						)
						(arc
							(start 0.2032 -0.3048)
							(mid 0.275042 -0.275042)
							(end 0.3048 -0.2032)
						)
					)
					(width 0)
					(fill yes)
				)
			)
		)
		(pad "2" smd custom
			(at 0 0.4445)
			(size 0.1524 0.1524)
			(layers "B.Cu" "B.Mask" "B.Paste")
			(net "GND")
			(options
				(clearance outline)
				(anchor circle)
			)
			(primitives
				(gr_poly
					(pts
						(arc
							(start 0.3048 0.2032)
							(mid 0.275042 0.275042)
							(end 0.2032 0.3048)
						)
						(arc
							(start -0.2032 0.3048)
							(mid -0.275042 0.275042)
							(end -0.3048 0.2032)
						)
						(arc
							(start -0.3048 -0.2032)
							(mid -0.275042 -0.275042)
							(end -0.2032 -0.3048)
						)
						(arc
							(start 0.2032 -0.3048)
							(mid 0.275042 -0.275042)
							(end 0.3048 -0.2032)
						)
					)
					(width 0)
					(fill yes)
				)
			)
		)
	)
	(footprint ""
		(layer "B.Cu")
		(at 378.587 -82.677 -90)
		(property "Reference" "C7W1"
			(at 0.8382 -0.67818 270)
			(unlocked yes)
			(layer "B.SilkS")
			(effects
				(font
					(size 0.4064 0.254)
					(thickness 0.1524)
				)
				(justify left mirror)
			)
		)
		(property "Value" ""
			(at 0 0 90)
			(layer "B.Fab")
			(effects
				(font
					(size 1.27 1.27)
				)
				(justify mirror)
			)
		)
		(duplicate_pad_numbers_are_jumpers no)
		(fp_poly
			(pts
				(xy -0.3048 -0.1016) (xy -0.3048 0.9906) (xy 0.3048 0.9906) (xy 0.3048 -0.1016)
			)
			(stroke
				(width 0)
				(type default)
			)
			(fill no)
			(layer "B.CrtYd")
		)
		(fp_line
			(start -0.3048 0.9906)
			(end -0.3048 -0.1016)
			(stroke
				(width 0.1)
				(type default)
			)
			(layer "B.Fab")
		)
		(fp_line
			(start 0.3048 0.9906)
			(end -0.3048 0.9906)
			(stroke
				(width 0.1)
				(type default)
			)
			(layer "B.Fab")
		)
		(fp_line
			(start -0.3048 -0.1016)
			(end 0.3048 -0.1016)
			(stroke
				(width 0.1)
				(type default)
			)
			(layer "B.Fab")
		)
		(fp_line
			(start 0.3048 -0.1016)
			(end 0.3048 0.9906)
			(stroke
				(width 0.1)
				(type default)
			)
			(layer "B.Fab")
		)
		(pad "1" smd rect
			(at 0 0 90)
			(size 0.508 0.508)
			(layers "B.Cu" "B.Mask" "B.Paste")
			(net "P3V3_STBY")
		)
		(pad "2" smd rect
			(at 0 0.889 90)
			(size 0.508 0.508)
			(layers "B.Cu" "B.Mask" "B.Paste")
			(net "GND")
		)
		(zone
			(layer "B.Cu")
			(hatch none 0.5)
			(connect_pads
				(clearance 0)
			)
			(min_thickness 0.25)
			(keepout
				(tracks not_allowed)
				(vias allowed)
				(pads allowed)
				(copperpour not_allowed)
				(footprints allowed)
			)
			(placement
				(enabled no)
				(sheetname "")
			)
			(fill
				(thermal_gap 0.5)
				(thermal_bridge_width 0.5)
				(island_removal_mode 0)
			)
			(polygon
				(pts
					(xy 377.952 -82.423) (xy 377.952 -82.931) (xy 378.333 -82.931) (xy 378.333 -82.423)
				)
			)
		)
		(zone
			(layer "B.Cu")
			(hatch none 0.5)
			(connect_pads
				(clearance 0)
			)
			(min_thickness 0.25)
			(keepout
				(tracks allowed)
				(vias not_allowed)
				(pads allowed)
				(copperpour not_allowed)
				(footprints allowed)
			)
			(placement
				(enabled no)
				(sheetname "")
			)
			(fill
				(thermal_gap 0.5)
				(thermal_bridge_width 0.5)
				(island_removal_mode 0)
			)
			(polygon
				(pts
					(xy 378.333 -82.423) (xy 378.333 -82.931) (xy 377.952 -82.931) (xy 377.952 -82.423)
				)
			)
		)
	)
	(footprint ""
		(layer "B.Cu")
		(at 272.861532 -12.954 90)
		(property "Reference" "C5G48"
			(at -1.14681 0.76708 180)
			(unlocked yes)
			(layer "B.SilkS")
			(effects
				(font
					(size 0.7874 0.5842)
					(thickness 0.1524)
				)
				(justify mirror)
			)
		)
		(property "Value" ""
			(at 0 0 90)
			(layer "B.Fab")
			(effects
				(font
					(size 1.27 1.27)
				)
				(justify mirror)
			)
		)
		(duplicate_pad_numbers_are_jumpers no)
		(fp_rect
			(start -0.4953 -0.2032)
			(end 0.4953 1.6002)
			(stroke
				(width 0)
				(type default)
			)
			(fill no)
			(layer "B.CrtYd")
		)
		(fp_line
			(start 0.4953 -0.2032)
			(end -0.4953 -0.2032)
			(stroke
				(width 0.1)
				(type default)
			)
			(layer "B.Fab")
		)
		(fp_line
			(start -0.4953 -0.2032)
			(end -0.4953 1.6002)
			(stroke
				(width 0.1)
				(type default)
			)
			(layer "B.Fab")
		)
		(fp_line
			(start 0.4953 1.6002)
			(end 0.4953 -0.2032)
			(stroke
				(width 0.1)
				(type default)
			)
			(layer "B.Fab")
		)
		(fp_line
			(start -0.4953 1.6002)
			(end 0.4953 1.6002)
			(stroke
				(width 0.1)
				(type default)
			)
			(layer "B.Fab")
		)
		(pad "1" smd rect
			(at 0 0 270)
			(size 0.762 0.889)
			(layers "B.Cu" "B.Mask" "B.Paste")
			(net "PVDDQ_ABC")
		)
		(pad "2" smd rect
			(at 0 1.397 270)
			(size 0.762 0.889)
			(layers "B.Cu" "B.Mask" "B.Paste")
			(net "GND")
		)
		(zone
			(layer "B.Cu")
			(hatch none 0.5)
			(connect_pads
				(clearance 0)
			)
			(min_thickness 0.25)
			(keepout
				(tracks not_allowed)
				(vias allowed)
				(pads allowed)
				(copperpour not_allowed)
				(footprints allowed)
			)
			(placement
				(enabled no)
				(sheetname "")
			)
			(fill
				(thermal_gap 0.5)
				(thermal_bridge_width 0.5)
				(island_removal_mode 0)
			)
			(polygon
				(pts
					(xy 273.306032 -12.573) (xy 273.814032 -12.573) (xy 273.814032 -13.335) (xy 273.306032 -13.335)
				)
			)
		)
	)
)
